# BASEBOARD_FAB2 (Tioga Pass) — schematic netlist excerpt (pin names and nets, part order shuffled) for the footprints in the layout excerpt that follows; sources: Cadence DE-HDL packaged netlist, KiCad conversion of Wiwynn_Tioga_Pass_MB.brd

Q9P1  FET_N_DUAL  2N7002DW FET  pkg SMLF  page 200
  SOURCE(0)  = GND
  GATE(0)  = A_HSC_LOW_GATE
  DRAIN(0)  = IRQ_UV_DETECT_N
  SOURCE(0)  = GND
  GATE(0)  = A_P12V_STBY_FPH_GATE
  DRAIN(0)  = A_HSC_LOW_DRAIN

R7C11  RES  1.0M 1% EMPTY  pkg 0402  page 137 : A = GND ; B = RST_RTCRST_N
R6W23  RES  1.00K 1% CHIP  pkg 0402  page 247 : A = PD_ID_EEPROM_WP ; B = GND

(kicad_pcb
	(version 20260206)
	(generator "pcbnew")
	(generator_version "10.0")
	(general
		(thickness 1.6)
		(legacy_teardrops no)
	)
	(paper "A4")
	(title_block
		(title "Wiwynn_Tioga_Pass_MB.brd")
		(comment 1 "Tioga Pass / footprints 3962-3964 of 4770")
	)
	(layers
		(0 "F.Cu" signal "TOP")
		(4 "In1.Cu" signal "L2GND")
		(6 "In2.Cu" signal "L3")
		(8 "In3.Cu" signal "L4GND")
		(10 "In4.Cu" signal "L5")
		(12 "In5.Cu" signal "L6GND")
		(14 "In6.Cu" signal "L7VCC")
		(16 "In7.Cu" signal "L8VCC")
		(18 "In8.Cu" signal "L9GND")
		(20 "In9.Cu" signal "L10")
		(22 "In10.Cu" signal "L11GND")
		(24 "In11.Cu" signal "L12")
		(26 "In12.Cu" signal "L13GND")
		(2 "B.Cu" signal "BOTTOM")
		(9 "F.Adhes" user "F.Adhesive")
		(11 "B.Adhes" user "B.Adhesive")
		(13 "F.Paste" user "Package Geometry/Pastemask Top")
		(15 "B.Paste" user "Package Geometry/Pastemask Bottom")
		(5 "F.SilkS" user "Ref Des/Silkscreen Top")
		(7 "B.SilkS" user "Ref Des/Silkscreen Bottom")
		(1 "F.Mask" user "Board Geometry/Soldermask Top")
		(3 "B.Mask" user "Board Geometry/Soldermask Bottom")
		(17 "Dwgs.User" user "User.Drawings")
		(19 "Cmts.User" user "User.Comments")
		(21 "Eco1.User" user "User.Eco1")
		(23 "Eco2.User" user "User.Eco2")
		(25 "Edge.Cuts" user "Board Geometry/Outline")
		(27 "Margin" user)
		(31 "F.CrtYd" user "Package Geometry/Place Bound Top")
		(29 "B.CrtYd" user "Package Geometry/Place Bound Bottom")
		(35 "F.Fab" user "Ref Des/Assembly Top")
		(33 "B.Fab" user "Ref Des/Assembly Bottom")
	)
	(footprint ""
		(layer "B.Cu")
		(at 372.609618 -88.89111 180)
		(property "Reference" "R7C11"
			(at 0 0 0)
			(layer "B.SilkS")
			(hide yes)
			(effects
				(font
					(size 1.27 1.27)
				)
				(justify mirror)
			)
		)
		(property "Value" ""
			(at 0 0 0)
			(layer "B.Fab")
			(effects
				(font
					(size 1.27 1.27)
				)
				(justify mirror)
			)
		)
		(duplicate_pad_numbers_are_jumpers no)
		(fp_poly
			(pts
				(xy 0.2794 -0.1016) (xy -0.2794 -0.1016) (xy -0.2794 0.9906) (xy 0.2794 0.9906)
			)
			(stroke
				(width 0)
				(type default)
			)
			(fill no)
			(layer "B.CrtYd")
		)
		(fp_line
			(start 0.2794 0.9906)
			(end -0.2794 0.9906)
			(stroke
				(width 0.1)
				(type default)
			)
			(layer "B.Fab")
		)
		(fp_line
			(start 0.2794 -0.1016)
			(end 0.2794 0.9906)
			(stroke
				(width 0.1)
				(type default)
			)
			(layer "B.Fab")
		)
		(fp_line
			(start -0.2794 0.9906)
			(end -0.2794 -0.1016)
			(stroke
				(width 0.1)
				(type default)
			)
			(layer "B.Fab")
		)
		(fp_line
			(start -0.2794 -0.1016)
			(end 0.2794 -0.1016)
			(stroke
				(width 0.1)
				(type default)
			)
			(layer "B.Fab")
		)
		(pad "1" smd rect
			(at 0 0)
			(size 0.508 0.508)
			(layers "B.Cu" "B.Mask" "B.Paste")
			(net "GND")
		)
		(pad "2" smd rect
			(at 0 0.889)
			(size 0.508 0.508)
			(layers "B.Cu" "B.Mask" "B.Paste")
			(net "RST_RTCRST_N")
		)
		(zone
			(layer "B.Cu")
			(hatch none 0.5)
			(connect_pads
				(clearance 0)
			)
			(min_thickness 0.25)
			(keepout
				(tracks not_allowed)
				(vias allowed)
				(pads allowed)
				(copperpour not_allowed)
				(footprints allowed)
			)
			(placement
				(enabled no)
				(sheetname "")
			)
			(fill
				(thermal_gap 0.5)
				(thermal_bridge_width 0.5)
				(island_removal_mode 0)
			)
			(polygon
				(pts
					(xy 372.355618 -89.52611) (xy 372.863618 -89.52611) (xy 372.863618 -89.14511) (xy 372.355618 -89.14511)
				)
			)
		)
		(zone
			(layer "B.Cu")
			(hatch none 0.5)
			(connect_pads
				(clearance 0)
			)
			(min_thickness 0.25)
			(keepout
				(tracks allowed)
				(vias not_allowed)
				(pads allowed)
				(copperpour not_allowed)
				(footprints allowed)
			)
			(placement
				(enabled no)
				(sheetname "")
			)
			(fill
				(thermal_gap 0.5)
				(thermal_bridge_width 0.5)
				(island_removal_mode 0)
			)
			(polygon
				(pts
					(xy 372.355618 -89.14511) (xy 372.863618 -89.14511) (xy 372.863618 -89.52611) (xy 372.355618 -89.52611)
				)
			)
		)
	)
	(footprint ""
		(layer "B.Cu")
		(at 16.0782 -84.455 90)
		(property "Reference" "Q9P1"
			(at -2.286 -1.37287 270)
			(unlocked yes)
			(layer "B.SilkS")
			(effects
				(font
					(size 0.7874 0.5842)
					(thickness 0.1524)
				)
				(justify left mirror)
			)
		)
		(property "Value" ""
			(at 0 0 90)
			(layer "B.Fab")
			(effects
				(font
					(size 1.27 1.27)
				)
				(justify mirror)
			)
		)
		(duplicate_pad_numbers_are_jumpers no)
		(fp_circle
			(center 0.848614 -0.6477)
			(end 0.848614 -0.5207)
			(stroke
				(width 0.254)
				(type default)
			)
			(fill no)
			(layer "B.SilkS")
		)
		(fp_poly
			(pts
				(xy -0.21463 -0.450088) (xy -1.56337 -0.450088) (xy -1.56337 1.75006) (xy -0.21463 1.75006)
			)
			(stroke
				(width 0)
				(type default)
			)
			(fill no)
			(layer "B.CrtYd")
		)
		(fp_line
			(start -0.21463 -0.450088)
			(end -1.56337 -0.450088)
			(stroke
				(width 0.1)
				(type default)
			)
			(layer "B.Fab")
		)
		(fp_line
			(start -1.56337 -0.450088)
			(end -1.56337 1.75006)
			(stroke
				(width 0.1)
				(type default)
			)
			(layer "B.Fab")
		)
		(fp_line
			(start -0.21463 1.75006)
			(end -0.21463 -0.450088)
			(stroke
				(width 0.1)
				(type default)
			)
			(layer "B.Fab")
		)
		(fp_line
			(start -1.56337 1.75006)
			(end -0.21463 1.75006)
			(stroke
				(width 0.1)
				(type default)
			)
			(layer "B.Fab")
		)
		(fp_circle
			(center 0.848614 -0.6477)
			(end 0.848614 -0.5207)
			(stroke
				(width 0.254)
				(type default)
			)
			(fill no)
			(layer "B.Fab")
		)
		(pad "1" smd rect
			(at 0 0 270)
			(size 1.016 0.381)
			(layers "B.Cu" "B.Mask" "B.Paste")
			(net "GND")
		)
		(pad "2" smd rect
			(at 0 0.649986 270)
			(size 1.016 0.381)
			(layers "B.Cu" "B.Mask" "B.Paste")
			(net "A_HSC_LOW_GATE")
		)
		(pad "3" smd rect
			(at 0 1.299972 270)
			(size 1.016 0.381)
			(layers "B.Cu" "B.Mask" "B.Paste")
			(net "IRQ_UV_DETECT_N")
		)
		(pad "4" smd rect
			(at -1.778 1.299972 270)
			(size 1.016 0.381)
			(layers "B.Cu" "B.Mask" "B.Paste")
			(net "GND")
		)
		(pad "5" smd rect
			(at -1.778 0.649986 270)
			(size 1.016 0.381)
			(layers "B.Cu" "B.Mask" "B.Paste")
			(net "A_P12V_STBY_FPH_GATE")
		)
		(pad "6" smd rect
			(at -1.778 0 270)
			(size 1.016 0.381)
			(layers "B.Cu" "B.Mask" "B.Paste")
			(net "A_HSC_LOW_DRAIN")
		)
	)
	(footprint ""
		(layer "B.Cu")
		(at 450.5325 -25.273 -90)
		(property "Reference" "R6W23"
			(at 0.8382 -0.67818 270)
			(unlocked yes)
			(layer "B.SilkS")
			(effects
				(font
					(size 0.4064 0.254)
					(thickness 0.1524)
				)
				(justify left mirror)
			)
		)
		(property "Value" ""
			(at 0 0 90)
			(layer "B.Fab")
			(effects
				(font
					(size 1.27 1.27)
				)
				(justify mirror)
			)
		)
		(duplicate_pad_numbers_are_jumpers no)
		(fp_poly
			(pts
				(xy 0.2794 -0.1016) (xy -0.2794 -0.1016) (xy -0.2794 0.9906) (xy 0.2794 0.9906)
			)
			(stroke
				(width 0)
				(type default)
			)
			(fill no)
			(layer "B.CrtYd")
		)
		(fp_line
			(start -0.2794 0.9906)
			(end -0.2794 -0.1016)
			(stroke
				(width 0.1)
				(type default)
			)
			(layer "B.Fab")
		)
		(fp_line
			(start 0.2794 0.9906)
			(end -0.2794 0.9906)
			(stroke
				(width 0.1)
				(type default)
			)
			(layer "B.Fab")
		)
		(fp_line
			(start -0.2794 -0.1016)
			(end 0.2794 -0.1016)
			(stroke
				(width 0.1)
				(type default)
			)
			(layer "B.Fab")
		)
		(fp_line
			(start 0.2794 -0.1016)
			(end 0.2794 0.9906)
			(stroke
				(width 0.1)
				(type default)
			)
			(layer "B.Fab")
		)
		(pad "1" smd rect
			(at 0 0 90)
			(size 0.508 0.508)
			(layers "B.Cu" "B.Mask" "B.Paste")
			(net "PD_ID_EEPROM_WP")
		)
		(pad "2" smd rect
			(at 0 0.889 90)
			(size 0.508 0.508)
			(layers "B.Cu" "B.Mask" "B.Paste")
			(net "GND")
		)
		(zone
			(layer "B.Cu")
			(hatch none 0.5)
			(connect_pads
				(clearance 0)
			)
			(min_thickness 0.25)
			(keepout
				(tracks not_allowed)
				(vias allowed)
				(pads allowed)
				(copperpour not_allowed)
				(footprints allowed)
			)
			(placement
				(enabled no)
				(sheetname "")
			)
			(fill
				(thermal_gap 0.5)
				(thermal_bridge_width 0.5)
				(island_removal_mode 0)
			)
			(polygon
				(pts
					(xy 449.8975 -25.019) (xy 449.8975 -25.527) (xy 450.2785 -25.527) (xy 450.2785 -25.019)
				)
			)
		)
		(zone
			(layer "B.Cu")
			(hatch none 0.5)
			(connect_pads
				(clearance 0)
			)
			(min_thickness 0.25)
			(keepout
				(tracks allowed)
				(vias not_allowed)
				(pads allowed)
				(copperpour not_allowed)
				(footprints allowed)
			)
			(placement
				(enabled no)
				(sheetname "")
			)
			(fill
				(thermal_gap 0.5)
				(thermal_bridge_width 0.5)
				(island_removal_mode 0)
			)
			(polygon
				(pts
					(xy 450.2785 -25.019) (xy 450.2785 -25.527) (xy 449.8975 -25.527) (xy 449.8975 -25.019)
				)
			)
		)
	)
)
